(kicad_pcb
	(version 20260206)
	(generator "pcbnew")
	(generator_version "10.0")
	(general
		(thickness 1.6)
		(legacy_teardrops no)
	)
	(paper "A4")
	(title_block
		(title "Bryce Canyon_R.DPB_16317-1_OCP.brd")
		(comment 1 "Bryce Canyon / footprints 1945-1953 of 2099")
	)
	(layers
		(0 "F.Cu" signal "TOP")
		(4 "In1.Cu" signal "L2GND")
		(6 "In2.Cu" signal "L3")
		(8 "In3.Cu" signal "L4VCC")
		(10 "In4.Cu" signal "L5VCC")
		(12 "In5.Cu" signal "L6")
		(14 "In6.Cu" signal "L7GND")
		(2 "B.Cu" signal "BOTTOM")
		(9 "F.Adhes" user "F.Adhesive")
		(11 "B.Adhes" user "B.Adhesive")
		(13 "F.Paste" user "Package Geometry/Pastemask Top")
		(15 "B.Paste" user "Package Geometry/Pastemask Bottom")
		(5 "F.SilkS" user "Ref Des/Silkscreen Top")
		(7 "B.SilkS" user "Ref Des/Silkscreen Bottom")
		(1 "F.Mask" user "Board Geometry/Soldermask Top")
		(3 "B.Mask" user "Board Geometry/Soldermask Bottom")
		(17 "Dwgs.User" user "User.Drawings")
		(19 "Cmts.User" user "User.Comments")
		(21 "Eco1.User" user "User.Eco1")
		(23 "Eco2.User" user "User.Eco2")
		(25 "Edge.Cuts" user "Board Geometry/Outline")
		(27 "Margin" user)
		(31 "F.CrtYd" user "Package Geometry/Place Bound Top")
		(29 "B.CrtYd" user "Package Geometry/Place Bound Bottom")
		(35 "F.Fab" user "Ref Des/Assembly Top")
		(33 "B.Fab" user "Ref Des/Assembly Bottom")
	)
	(footprint ""
		(layer "F.Cu")
		(at 461.899 -246.761 180)
		(property "Reference" "R331"
			(at 0 0 180)
			(layer "F.SilkS")
			(hide yes)
			(effects
				(font
					(size 1.27 1.27)
				)
			)
		)
		(property "Value" "0R2J-2-GP"
			(at 0.064008 -3.993896 180)
			(unlocked yes)
			(layer "F.Fab")
			(hide yes)
			(effects
				(font
					(size 1.016 1.016)
					(thickness 0.1524)
				)
			)
		)
		(property "Device Type" "R402H16"
			(at 0.064008 -5.517896 180)
			(unlocked yes)
			(layer "F.Fab")
			(hide yes)
			(effects
				(font
					(size 1.016 1.016)
					(thickness 0.1524)
				)
			)
		)
		(duplicate_pad_numbers_are_jumpers no)
		(fp_line
			(start 0.508 -0.9398)
			(end -0.508 -0.9398)
			(stroke
				(width 0.1524)
				(type default)
			)
			(layer "F.SilkS")
		)
		(fp_line
			(start -0.508 -0.9398)
			(end -0.508 0.9398)
			(stroke
				(width 0.1524)
				(type default)
			)
			(layer "F.SilkS")
		)
		(fp_rect
			(start -0.508 0.9398)
			(end 0.508 -0.9398)
			(stroke
				(width 0)
				(type default)
			)
			(fill no)
			(layer "F.CrtYd")
		)
		(fp_rect
			(start -0.508 0.9398)
			(end 0.508 -0.9398)
			(stroke
				(width 0)
				(type default)
			)
			(fill no)
			(layer "F.Fab")
		)
		(pad "1" smd custom
			(at 0 -0.4445 180)
			(size 0.1397 0.1397)
			(layers "F.Cu" "F.Mask" "F.Paste")
			(net "SW_HDD_G10")
			(options
				(clearance outline)
				(anchor circle)
			)
			(primitives
				(gr_poly
					(pts
						(arc
							(start -0.1778 -0.2794)
							(mid -0.249642 -0.249642)
							(end -0.2794 -0.1778)
						)
						(arc
							(start -0.2794 0.1778)
							(mid -0.249642 0.249642)
							(end -0.1778 0.2794)
						)
						(arc
							(start 0.1778 0.2794)
							(mid 0.249642 0.249642)
							(end 0.2794 0.1778)
						)
						(arc
							(start 0.2794 -0.1778)
							(mid 0.249642 -0.249642)
							(end 0.1778 -0.2794)
						)
					)
					(width 0)
					(fill yes)
				)
			)
		)
		(pad "2" smd custom
			(at 0 0.4445 180)
			(size 0.1397 0.1397)
			(layers "F.Cu" "F.Mask" "F.Paste")
			(net "SW_HDD_R10")
			(options
				(clearance outline)
				(anchor circle)
			)
			(primitives
				(gr_poly
					(pts
						(arc
							(start -0.1778 -0.2794)
							(mid -0.249642 -0.249642)
							(end -0.2794 -0.1778)
						)
						(arc
							(start -0.2794 0.1778)
							(mid -0.249642 0.249642)
							(end -0.1778 0.2794)
						)
						(arc
							(start 0.1778 0.2794)
							(mid 0.249642 0.249642)
							(end 0.2794 0.1778)
						)
						(arc
							(start 0.2794 -0.1778)
							(mid 0.249642 -0.249642)
							(end 0.1778 -0.2794)
						)
					)
					(width 0)
					(fill yes)
				)
			)
		)
	)
	(footprint ""
		(layer "B.Cu")
		(at 448.018408 -120.594882 -90)
		(property "Reference" "C683"
			(at 0 0 90)
			(layer "B.SilkS")
			(hide yes)
			(effects
				(font
					(size 1.27 1.27)
				)
				(justify mirror)
			)
		)
		(property "Value" "SC470P50V2KX-3GP"
			(at -1.1811 -2.7051 270)
			(unlocked yes)
			(layer "B.Fab")
			(hide yes)
			(effects
				(font
					(size 1.016 1.016)
					(thickness 0.1524)
				)
				(justify mirror)
			)
		)
		(property "Device Type" "C402H22"
			(at -1.1811 -4.2291 270)
			(unlocked yes)
			(layer "B.Fab")
			(hide yes)
			(effects
				(font
					(size 1.016 1.016)
					(thickness 0.1524)
				)
				(justify mirror)
			)
		)
		(duplicate_pad_numbers_are_jumpers no)
		(fp_rect
			(start 0.4318 0.9525)
			(end -0.4318 -0.9525)
			(stroke
				(width 0)
				(type default)
			)
			(fill no)
			(layer "B.CrtYd")
		)
		(fp_rect
			(start 0.4318 0.9525)
			(end -0.4318 -0.9525)
			(stroke
				(width 0)
				(type default)
			)
			(fill no)
			(layer "B.Fab")
		)
		(pad "1" smd custom
			(at 0 -0.4445 90)
			(size 0.1524 0.1524)
			(layers "B.Cu" "B.Mask" "B.Paste")
			(net "P5V_B_4_LL_R")
			(options
				(clearance outline)
				(anchor circle)
			)
			(primitives
				(gr_poly
					(pts
						(arc
							(start 0.3048 0.2032)
							(mid 0.275042 0.275042)
							(end 0.2032 0.3048)
						)
						(arc
							(start -0.2032 0.3048)
							(mid -0.275042 0.275042)
							(end -0.3048 0.2032)
						)
						(arc
							(start -0.3048 -0.2032)
							(mid -0.275042 -0.275042)
							(end -0.2032 -0.3048)
						)
						(arc
							(start 0.2032 -0.3048)
							(mid 0.275042 -0.275042)
							(end 0.3048 -0.2032)
						)
					)
					(width 0)
					(fill yes)
				)
			)
		)
		(pad "2" smd custom
			(at 0 0.4445 90)
			(size 0.1524 0.1524)
			(layers "B.Cu" "B.Mask" "B.Paste")
			(net "P5V_B_4_VFB")
			(options
				(clearance outline)
				(anchor circle)
			)
			(primitives
				(gr_poly
					(pts
						(arc
							(start 0.3048 0.2032)
							(mid 0.275042 0.275042)
							(end 0.2032 0.3048)
						)
						(arc
							(start -0.2032 0.3048)
							(mid -0.275042 0.275042)
							(end -0.3048 0.2032)
						)
						(arc
							(start -0.3048 -0.2032)
							(mid -0.275042 -0.275042)
							(end -0.2032 -0.3048)
						)
						(arc
							(start 0.2032 -0.3048)
							(mid 0.275042 -0.275042)
							(end 0.3048 -0.2032)
						)
					)
					(width 0)
					(fill yes)
				)
			)
		)
	)
	(footprint ""
		(layer "B.Cu")
		(at 243.967 -286.004 180)
		(property "Reference" "C706"
			(at 0 0 0)
			(layer "B.SilkS")
			(hide yes)
			(effects
				(font
					(size 1.27 1.27)
				)
				(justify mirror)
			)
		)
		(property "Value" "SC10U6D3V5KX-4GP"
			(at 0.0762 -6.1214 180)
			(unlocked yes)
			(layer "B.Fab")
			(hide yes)
			(effects
				(font
					(size 1.016 1.016)
					(thickness 0.1524)
				)
				(justify mirror)
			)
		)
		(property "Device Type" "C805H58"
			(at 0.0762 -8.1534 180)
			(unlocked yes)
			(layer "B.Fab")
			(hide yes)
			(effects
				(font
					(size 1.016 1.016)
					(thickness 0.1524)
				)
				(justify mirror)
			)
		)
		(duplicate_pad_numbers_are_jumpers no)
		(fp_line
			(start -0.635 0)
			(end 0.635 0)
			(stroke
				(width 0.508)
				(type default)
			)
			(layer "B.SilkS")
		)
		(fp_rect
			(start 0.9652 1.778)
			(end -0.9652 -1.778)
			(stroke
				(width 0)
				(type default)
			)
			(fill no)
			(layer "B.CrtYd")
		)
		(fp_poly
			(pts
				(xy 0.9652 -1.778) (xy -0.9652 -1.778) (xy -0.9652 1.778) (xy 0.9652 1.778)
			)
			(stroke
				(width 0)
				(type default)
			)
			(fill no)
			(layer "B.Fab")
		)
		(pad "1" smd rect
			(at 0 -0.9652)
			(size 1.397 1.143)
			(layers "B.Cu" "B.Mask" "B.Paste")
			(net "P3V3_STBY_B")
		)
		(pad "2" smd rect
			(at 0 0.9652)
			(size 1.397 1.143)
			(layers "B.Cu" "B.Mask" "B.Paste")
			(net "GND")
		)
	)
	(footprint ""
		(layer "B.Cu")
		(at 449.005198 -118.777004 180)
		(property "Reference" "C680"
			(at 0 0 0)
			(layer "B.SilkS")
			(hide yes)
			(effects
				(font
					(size 1.27 1.27)
				)
				(justify mirror)
			)
		)
		(property "Value" "SCD1U50V3KX-GP"
			(at 0 -2.8194 180)
			(unlocked yes)
			(layer "B.Fab")
			(hide yes)
			(effects
				(font
					(size 1.016 1.016)
					(thickness 0.1524)
				)
				(justify mirror)
			)
		)
		(property "Device Type" "C603H36"
			(at 0 -4.3434 180)
			(unlocked yes)
			(layer "B.Fab")
			(hide yes)
			(effects
				(font
					(size 1.016 1.016)
					(thickness 0.1524)
				)
				(justify mirror)
			)
		)
		(duplicate_pad_numbers_are_jumpers no)
		(fp_line
			(start -0.508 0)
			(end 0.508 0)
			(stroke
				(width 0.2032)
				(type default)
			)
			(layer "B.SilkS")
		)
		(fp_rect
			(start 0.5842 1.3335)
			(end -0.5842 -1.3335)
			(stroke
				(width 0)
				(type default)
			)
			(fill no)
			(layer "B.CrtYd")
		)
		(fp_rect
			(start 0.5842 1.3335)
			(end -0.5842 -1.3335)
			(stroke
				(width 0)
				(type default)
			)
			(fill no)
			(layer "B.Fab")
		)
		(pad "1" smd custom
			(at 0 -0.762)
			(size 0.2159 0.2159)
			(layers "B.Cu" "B.Mask" "B.Paste")
			(net "P5V_B_4")
			(options
				(clearance outline)
				(anchor circle)
			)
			(primitives
				(gr_poly
					(pts
						(arc
							(start -0.3302 0.4318)
							(mid -0.402042 0.402042)
							(end -0.4318 0.3302)
						)
						(arc
							(start -0.4318 -0.3302)
							(mid -0.402042 -0.402042)
							(end -0.3302 -0.4318)
						)
						(arc
							(start 0.3302 -0.4318)
							(mid 0.402042 -0.402042)
							(end 0.4318 -0.3302)
						)
						(arc
							(start 0.4318 0.3302)
							(mid 0.402042 0.402042)
							(end 0.3302 0.4318)
						)
					)
					(width 0)
					(fill yes)
				)
			)
		)
		(pad "2" smd custom
			(at 0 0.762)
			(size 0.2159 0.2159)
			(layers "B.Cu" "B.Mask" "B.Paste")
			(net "P5V_B_4_LL_R")
			(options
				(clearance outline)
				(anchor circle)
			)
			(primitives
				(gr_poly
					(pts
						(arc
							(start -0.3302 0.4318)
							(mid -0.402042 0.402042)
							(end -0.4318 0.3302)
						)
						(arc
							(start -0.4318 -0.3302)
							(mid -0.402042 -0.402042)
							(end -0.3302 -0.4318)
						)
						(arc
							(start 0.3302 -0.4318)
							(mid 0.402042 -0.402042)
							(end 0.4318 -0.3302)
						)
						(arc
							(start 0.4318 0.3302)
							(mid 0.402042 0.402042)
							(end 0.3302 0.4318)
						)
					)
					(width 0)
					(fill yes)
				)
			)
		)
	)
	(footprint ""
		(layer "B.Cu")
		(at 482.285802 -228.35235 180)
		(property "Reference" "C670"
			(at 0 0 0)
			(layer "B.SilkS")
			(hide yes)
			(effects
				(font
					(size 1.27 1.27)
				)
				(justify mirror)
			)
		)
		(property "Value" "SC10U16V5KX-7-GP-U"
			(at 0.0762 -6.1214 180)
			(unlocked yes)
			(layer "B.Fab")
			(hide yes)
			(effects
				(font
					(size 1.016 1.016)
					(thickness 0.1524)
				)
				(justify mirror)
			)
		)
		(property "Device Type" "C805H58"
			(at 0.0762 -8.1534 180)
			(unlocked yes)
			(layer "B.Fab")
			(hide yes)
			(effects
				(font
					(size 1.016 1.016)
					(thickness 0.1524)
				)
				(justify mirror)
			)
		)
		(duplicate_pad_numbers_are_jumpers no)
		(fp_line
			(start -0.635 0)
			(end 0.635 0)
			(stroke
				(width 0.508)
				(type default)
			)
			(layer "B.SilkS")
		)
		(fp_rect
			(start 0.9652 1.778)
			(end -0.9652 -1.778)
			(stroke
				(width 0)
				(type default)
			)
			(fill no)
			(layer "B.CrtYd")
		)
		(fp_poly
			(pts
				(xy 0.9652 -1.778) (xy -0.9652 -1.778) (xy -0.9652 1.778) (xy 0.9652 1.778)
			)
			(stroke
				(width 0)
				(type default)
			)
			(fill no)
			(layer "B.Fab")
		)
		(pad "1" smd rect
			(at 0 -0.9652)
			(size 1.397 1.143)
			(layers "B.Cu" "B.Mask" "B.Paste")
			(net "P5V_B_3")
		)
		(pad "2" smd rect
			(at 0 0.9652)
			(size 1.397 1.143)
			(layers "B.Cu" "B.Mask" "B.Paste")
			(net "GND")
		)
	)
	(footprint ""
		(layer "B.Cu")
		(at 56.155082 -119.72671 -90)
		(property "Reference" "C647"
			(at 0 0 90)
			(layer "B.SilkS")
			(hide yes)
			(effects
				(font
					(size 1.27 1.27)
				)
				(justify mirror)
			)
		)
		(property "Value" "SC470P50V2KX-3GP"
			(at -1.1811 -2.7051 270)
			(unlocked yes)
			(layer "B.Fab")
			(hide yes)
			(effects
				(font
					(size 1.016 1.016)
					(thickness 0.1524)
				)
				(justify mirror)
			)
		)
		(property "Device Type" "C402H22"
			(at -1.1811 -4.2291 270)
			(unlocked yes)
			(layer "B.Fab")
			(hide yes)
			(effects
				(font
					(size 1.016 1.016)
					(thickness 0.1524)
				)
				(justify mirror)
			)
		)
		(duplicate_pad_numbers_are_jumpers no)
		(fp_rect
			(start 0.4318 0.9525)
			(end -0.4318 -0.9525)
			(stroke
				(width 0)
				(type default)
			)
			(fill no)
			(layer "B.CrtYd")
		)
		(fp_rect
			(start 0.4318 0.9525)
			(end -0.4318 -0.9525)
			(stroke
				(width 0)
				(type default)
			)
			(fill no)
			(layer "B.Fab")
		)
		(pad "1" smd custom
			(at 0 -0.4445 90)
			(size 0.1524 0.1524)
			(layers "B.Cu" "B.Mask" "B.Paste")
			(net "P5V_B_2_LL_R")
			(options
				(clearance outline)
				(anchor circle)
			)
			(primitives
				(gr_poly
					(pts
						(arc
							(start 0.3048 0.2032)
							(mid 0.275042 0.275042)
							(end 0.2032 0.3048)
						)
						(arc
							(start -0.2032 0.3048)
							(mid -0.275042 0.275042)
							(end -0.3048 0.2032)
						)
						(arc
							(start -0.3048 -0.2032)
							(mid -0.275042 -0.275042)
							(end -0.2032 -0.3048)
						)
						(arc
							(start 0.2032 -0.3048)
							(mid 0.275042 -0.275042)
							(end 0.3048 -0.2032)
						)
					)
					(width 0)
					(fill yes)
				)
			)
		)
		(pad "2" smd custom
			(at 0 0.4445 90)
			(size 0.1524 0.1524)
			(layers "B.Cu" "B.Mask" "B.Paste")
			(net "P5V_B_2_VFB")
			(options
				(clearance outline)
				(anchor circle)
			)
			(primitives
				(gr_poly
					(pts
						(arc
							(start 0.3048 0.2032)
							(mid 0.275042 0.275042)
							(end 0.2032 0.3048)
						)
						(arc
							(start -0.2032 0.3048)
							(mid -0.275042 0.275042)
							(end -0.3048 0.2032)
						)
						(arc
							(start -0.3048 -0.2032)
							(mid -0.275042 -0.275042)
							(end -0.2032 -0.3048)
						)
						(arc
							(start 0.2032 -0.3048)
							(mid 0.275042 -0.275042)
							(end 0.3048 -0.2032)
						)
					)
					(width 0)
					(fill yes)
				)
			)
		)
	)
	(footprint ""
		(layer "B.Cu")
		(at 8.194802 -222.51035 180)
		(property "Reference" "R1098"
			(at 0 0 0)
			(layer "B.SilkS")
			(hide yes)
			(effects
				(font
					(size 1.27 1.27)
				)
				(justify mirror)
			)
		)
		(property "Value" "2D2R3-1-U-GP"
			(at 0.0254 -2.5146 180)
			(unlocked yes)
			(layer "B.Fab")
			(hide yes)
			(effects
				(font
					(size 1.016 1.016)
					(thickness 0.1524)
				)
				(justify mirror)
			)
		)
		(property "Device Type" "R603H22"
			(at 0.0254 -4.0386 180)
			(unlocked yes)
			(layer "B.Fab")
			(hide yes)
			(effects
				(font
					(size 1.016 1.016)
					(thickness 0.1524)
				)
				(justify mirror)
			)
		)
		(duplicate_pad_numbers_are_jumpers no)
		(fp_line
			(start 0.4826 0)
			(end 0.2032 0)
			(stroke
				(width 0.2032)
				(type default)
			)
			(layer "B.SilkS")
		)
		(fp_line
			(start -0.2032 0)
			(end -0.4826 0)
			(stroke
				(width 0.2032)
				(type default)
			)
			(layer "B.SilkS")
		)
		(fp_rect
			(start 0.5842 1.3335)
			(end -0.5842 -1.3335)
			(stroke
				(width 0)
				(type default)
			)
			(fill no)
			(layer "B.CrtYd")
		)
		(fp_rect
			(start 0.5842 1.3335)
			(end -0.5842 -1.3335)
			(stroke
				(width 0)
				(type default)
			)
			(fill no)
			(layer "B.Fab")
		)
		(pad "1" smd custom
			(at 0 -0.762)
			(size 0.2159 0.2159)
			(layers "B.Cu" "B.Mask" "B.Paste")
			(net "P12V_B")
			(options
				(clearance outline)
				(anchor circle)
			)
			(primitives
				(gr_poly
					(pts
						(arc
							(start -0.3302 0.4318)
							(mid -0.402042 0.402042)
							(end -0.4318 0.3302)
						)
						(arc
							(start -0.4318 -0.3302)
							(mid -0.402042 -0.402042)
							(end -0.3302 -0.4318)
						)
						(arc
							(start 0.3302 -0.4318)
							(mid 0.402042 -0.402042)
							(end 0.4318 -0.3302)
						)
						(arc
							(start 0.4318 0.3302)
							(mid 0.402042 0.402042)
							(end 0.3302 0.4318)
						)
					)
					(width 0)
					(fill yes)
				)
			)
		)
		(pad "2" smd custom
			(at 0 0.762)
			(size 0.2159 0.2159)
			(layers "B.Cu" "B.Mask" "B.Paste")
			(net "P12V_B_1_VDD_U31")
			(options
				(clearance outline)
				(anchor circle)
			)
			(primitives
				(gr_poly
					(pts
						(arc
							(start -0.3302 0.4318)
							(mid -0.402042 0.402042)
							(end -0.4318 0.3302)
						)
						(arc
							(start -0.4318 -0.3302)
							(mid -0.402042 -0.402042)
							(end -0.3302 -0.4318)
						)
						(arc
							(start 0.3302 -0.4318)
							(mid 0.402042 -0.402042)
							(end 0.4318 -0.3302)
						)
						(arc
							(start 0.4318 0.3302)
							(mid 0.402042 0.402042)
							(end 0.3302 0.4318)
						)
					)
					(width 0)
					(fill yes)
				)
			)
		)
	)
	(footprint ""
		(layer "B.Cu")
		(at 480.253802 -228.35235 180)
		(property "Reference" "C668"
			(at 0 0 0)
			(layer "B.SilkS")
			(hide yes)
			(effects
				(font
					(size 1.27 1.27)
				)
				(justify mirror)
			)
		)
		(property "Value" "SC10U16V5KX-7-GP-U"
			(at 0.0762 -6.1214 180)
			(unlocked yes)
			(layer "B.Fab")
			(hide yes)
			(effects
				(font
					(size 1.016 1.016)
					(thickness 0.1524)
				)
				(justify mirror)
			)
		)
		(property "Device Type" "C805H58"
			(at 0.0762 -8.1534 180)
			(unlocked yes)
			(layer "B.Fab")
			(hide yes)
			(effects
				(font
					(size 1.016 1.016)
					(thickness 0.1524)
				)
				(justify mirror)
			)
		)
		(duplicate_pad_numbers_are_jumpers no)
		(fp_line
			(start -0.635 0)
			(end 0.635 0)
			(stroke
				(width 0.508)
				(type default)
			)
			(layer "B.SilkS")
		)
		(fp_rect
			(start 0.9652 1.778)
			(end -0.9652 -1.778)
			(stroke
				(width 0)
				(type default)
			)
			(fill no)
			(layer "B.CrtYd")
		)
		(fp_poly
			(pts
				(xy 0.9652 -1.778) (xy -0.9652 -1.778) (xy -0.9652 1.778) (xy 0.9652 1.778)
			)
			(stroke
				(width 0)
				(type default)
			)
			(fill no)
			(layer "B.Fab")
		)
		(pad "1" smd rect
			(at 0 -0.9652)
			(size 1.397 1.143)
			(layers "B.Cu" "B.Mask" "B.Paste")
			(net "P5V_B_3")
		)
		(pad "2" smd rect
			(at 0 0.9652)
			(size 1.397 1.143)
			(layers "B.Cu" "B.Mask" "B.Paste")
			(net "GND")
		)
	)
	(footprint ""
		(layer "B.Cu")
		(at 69.49186 -117.167406 180)
		(property "Reference" "C650"
			(at 0 0 0)
			(layer "B.SilkS")
			(hide yes)
			(effects
				(font
					(size 1.27 1.27)
				)
				(justify mirror)
			)
		)
		(property "Value" "SC10U16V5KX-7-GP-U"
			(at 0.0762 -6.1214 180)
			(unlocked yes)
			(layer "B.Fab")
			(hide yes)
			(effects
				(font
					(size 1.016 1.016)
					(thickness 0.1524)
				)
				(justify mirror)
			)
		)
		(property "Device Type" "C805H58"
			(at 0.0762 -8.1534 180)
			(unlocked yes)
			(layer "B.Fab")
			(hide yes)
			(effects
				(font
					(size 1.016 1.016)
					(thickness 0.1524)
				)
				(justify mirror)
			)
		)
		(duplicate_pad_numbers_are_jumpers no)
		(fp_line
			(start -0.635 0)
			(end 0.635 0)
			(stroke
				(width 0.508)
				(type default)
			)
			(layer "B.SilkS")
		)
		(fp_rect
			(start 0.9652 1.778)
			(end -0.9652 -1.778)
			(stroke
				(width 0)
				(type default)
			)
			(fill no)
			(layer "B.CrtYd")
		)
		(fp_poly
			(pts
				(xy 0.9652 -1.778) (xy -0.9652 -1.778) (xy -0.9652 1.778) (xy 0.9652 1.778)
			)
			(stroke
				(width 0)
				(type default)
			)
			(fill no)
			(layer "B.Fab")
		)
		(pad "1" smd rect
			(at 0 -0.9652)
			(size 1.397 1.143)
			(layers "B.Cu" "B.Mask" "B.Paste")
			(net "P5V_B_2")
		)
		(pad "2" smd rect
			(at 0 0.9652)
			(size 1.397 1.143)
			(layers "B.Cu" "B.Mask" "B.Paste")
			(net "GND")
		)
	)
)
